FILE_TYPE = CONNECTIVITY;
{Allegro Design Entry HDL 17.4-2019 S026 (4007227) 1/17/2022}
"PAGE_NUMBER" = 307;
0"NC";
1"GND\g";
2"GND\g";
3"GND\g"CDS_PHYS_NET_NAME"GND"VOLTAGE"0";
4"GND\g";
5"GND\g"CDS_PHYS_NET_NAME"GND"VOLTAGE"0";
6"GND\g";
7"GND\g";
8"FM_NCSI_OCP_V3_2_R_OE";
9"FB_BMC_ISOLATE1";
10"FB_BMC_ISOLATE_R2";
11"P3V3_AUX\g";
12"OCP_V3_2_AUX_PWR_EN_R1"CDS_PHYS_NET_NAME"OCP_V3_2_AUX_PWR_EN_R1";
13"FM_OCP_V3_2_PWR_GOOD"CDS_PHYS_NET_NAME"FM_OCP_SFF_PWR_GOOD";
14"OCP_V3_2_ISO_BIF2_EN"CDS_PHYS_NET_NAME"OCP_SFF_ISO_BIF2_EN";
15"NCSI_OCP_V3_2_TX_EN";
16"NCSI_BMC_RXD1_R1";
17"RMII_OCP_BMC_RXD_1";
18"RMII_BMC_OCP_TXD_0";
19"RMII_BMC_OCP_TXD_1";
20"OCP_V3_2_RBT_ARB_IN_R"CDS_PHYS_NET_NAME"OCP_SFF_RBT_ARB_IN";
21"RMII_OCP_BMC_RXD_0";
22"NCSI_BMC_RXD0_R1"CDS_PHYS_NET_NAME"NCSI_BMC_RXD0_R";
23"NCSI_OCP_V3_2_RXD0"CDS_PHYS_NET_NAME"NCSI_OCP_SFF_RXD0";
24"RMII_BMC_OCP_TX_EN";
25"OCP_V3_2_RBT_ARB_IN";
26"NCSI_OCP_V3_2_CRS_DV"CDS_PHYS_NET_NAME"NCSI_OCP_SFF_CRS_DV";
27"P3V3_AUX\g"$PHYS_NET_NAME"P3V3_AUX"VOLTAGE"3.3"CDS_PHYS_NET_NAME"P3V3_AUX"$PHYS_NET_NAME"P3V3_AUX"VOLTAGE"3.3"CDS_PHYS_NET_NAME"P3V3_AUX";
28"NCSI_BMC_CRS_DV_R1"CDS_PHYS_NET_NAME"NCSI_BMC_CRS_DV_R";
29"NCSI_OCP_V3_2_RXD1";
30"OCP_V3_2_ISO2_RBT_ARB_OUT";
31"NCSI_OCP_V3_2_TXD0";
32"OCP_V3_2_ISO_BIF1_EN"CDS_PHYS_NET_NAME"OCP_SFF_ISO_BIF1_EN";
33"OCP_V3_2_ISO_BIF0_EN"CDS_PHYS_NET_NAME"OCP_SFF_ISO_BIF0_EN";
34"GND\g"VOLTAGE"0";
35"P3V3_AUX\g"$PHYS_NET_NAME"P3V3_AUX"VOLTAGE"3.3"CDS_PHYS_NET_NAME"P3V3_AUX"$PHYS_NET_NAME"P3V3_AUX"VOLTAGE"3.3"CDS_PHYS_NET_NAME"P3V3_AUX";
36"RMII_OCP_BMC_CRSDV";
37"OCP_V3_2_AUX_PWR_EN"CDS_PHYS_NET_NAME"OCP_V3_2_AUX_PWR_EN";
38"NCSI_OCP_V3_2_TXD1";
39"NCSI_BMC_TXD1_R1";
40"NCSI_BMC_TXD0_R1";
41"NCSI_BMC_TX_EN_R1";
42"OCP_V3_2_RBT_ARB_OUT";
43"OCP_V3_2_ISO1_RBT_ARB_IN"CDS_PHYS_NET_NAME"OCP_SFF_ISO_RBT_ARB_IN";
%"UNIVERSAL_GND"
"1","(275,-850)","0","pure_quanta_power","I14";
;
CDS_LIB"pure_quanta_power"
HDL_POWER"GND";
"A"1;
%"Q_RES"
"2","(275,-625)","0","pure_quanta","I15";
;
LOCATION"R3207"
$SEC"1"
CDS_SEC"1"
TOLERANCE"1%"
VALUE"100K"
WATTAGE"1/16W"
MATERIAL"CHIP"
PACK_TYPE"0402LF"
CDS_LIB"pure_quanta"
PART_NUMBER"CS41002FB09";
"A"
$PN"1"9;
"B"
$PN"2"1;
%"Q_CAP"
"1","(-1600,-25)","2","pure_quanta","I17";
;
LOCATION"C1825"
$SEC"1"
CDS_SEC"1"
PACK_TYPE"0402"
TOLERANCE"10%"
VALUE"0.1UF"
VOLTAGE"25V"
MATERIAL"X7R"
CDS_LIB"pure_quanta"
PART_NUMBER"CH4104K1B00";
"B"
$PN"2"2;
"A"
$PN"1"11;
%"UNIVERSAL_GND"
"1","(-1600,-250)","0","pure_quanta_power","I18";
;
CDS_LIB"pure_quanta_power"
HDL_POWER"GND";
"A"2;
%"UNIVERSAL_POWER"
"1","(-1600,250)","0","pure_quanta_power","I19";
;
HDL_POWER"P3V3_AUX"
CDS_LIB"pure_quanta_power";
"A"11;
%"UNIVERSAL_GND"
"1","(-325,425)","0","pure_quanta_power","I24";
;
CDS_LIB"pure_quanta_power"
HDL_POWER"GND";
"A"3;
%"UNIVERSAL_GND"
"1","(-525,1150)","0","pure_quanta_power","I25";
;
CDS_LIB"pure_quanta_power"
HDL_POWER"GND";
"A"4;
%"UNIVERSAL_POWER"
"1","(-325,1700)","0","pure_quanta_power","I26";
;
HDL_POWER"P3V3_AUX"
CDS_LIB"pure_quanta_power";
"A"35;
%"UNIVERSAL_GND"
"1","(-325,1850)","0","pure_quanta_power","I31";
;
CDS_LIB"pure_quanta_power"
HDL_POWER"GND";
"A"5;
%"74CBTLV3126PW"
"1","(225,2275)","2","pure_quanta","I32";
;
LOCATION"U222"
$SEC"1"
CDS_SEC"1"
VALUE"74CBTLV3126PW"
PART_TYPE"SMLF"
MATERIAL"IC"
CDS_LIB"pure_quanta"
NEEDS_NO_SIZE"TRUE"
CDS_LMAN_SYM_OUTLINE"-250,350,250,-350"
PART_NUMBER"AL003126K08";
"VCC"
$PN"14"27;
"4OE"
$PN"13"9;
"4A"
$PN"12"20;
"4B"
$PN"11"43;
"3OE"
$PN"10"9;
"3A"
$PN"9"28;
"GND"
$PN"7"5;
"1A"
$PN"2"16;
"2B"
$PN"6"23;
"1B"
$PN"3"29;
"2OE"
$PN"4"9;
"1OE"
$PN"1"9;
"3B"
$PN"8"26;
"2A"
$PN"5"22;
%"Q_CAP"
"1","(-525,2800)","2","pure_quanta","I33";
;
LOCATION"C1826"
$SEC"1"
CDS_SEC"1"
TOLERANCE"10%"
MATERIAL"X7R"
VOLTAGE"25V"
VALUE"0.1UF"
PACK_TYPE"0402"
CDS_LIB"pure_quanta"
PART_NUMBER"CH4104K1B00";
"B"
$PN"2"6;
"A"
$PN"1"27;
%"UNIVERSAL_GND"
"1","(-525,2575)","0","pure_quanta_power","I34";
;
CDS_LIB"pure_quanta_power"
HDL_POWER"GND";
"A"6;
%"UNIVERSAL_POWER"
"1","(-325,3125)","0","pure_quanta_power","I35";
;
HDL_POWER"P3V3_AUX"
CDS_LIB"pure_quanta_power";
"A"27;
%"Q_RES"
"2","(1800,-2525)","0","pure_quanta","I37";
;
LOCATION"R3208"
$SEC"1"
CDS_SEC"1"
MATERIAL"CHIP"
PACK_TYPE"0402LF"
WATTAGE"1/16W"
TOLERANCE"1%"
VALUE"100"
CDS_LIB"pure_quanta"
PART_NUMBER"CS11002FB07";
"A"
$PN"1"33;
"B"
$PN"2"34;
%"Q_RES"
"2","(2050,-2525)","0","pure_quanta","I38";
;
LOCATION"R3216"
$SEC"1"
CDS_SEC"1"
PACK_TYPE"0402LF"
WATTAGE"1/16W"
TOLERANCE"1%"
VALUE"100"
MATERIAL"CHIP"
CDS_LIB"pure_quanta"
PART_NUMBER"CS11002FB07";
"A"
$PN"1"32;
"B"
$PN"2"34;
%"UNIVERSAL_GND"
"1","(1800,-2800)","0","pure_quanta_power","I39";
;
CDS_LIB"pure_quanta_power"
HDL_POWER"GND";
"A"34;
%"Q_RES"
"2","(2300,-2525)","0","pure_quanta","I40";
;
LOCATION"R3217"
$SEC"1"
CDS_SEC"1"
PACK_TYPE"0402LF"
WATTAGE"1/16W"
MATERIAL"CHIP"
VALUE"100"
TOLERANCE"1%"
CDS_LIB"pure_quanta"
PART_NUMBER"CS11002FB07";
"A"
$PN"1"14;
"B"
$PN"2"34;
%"Q_RES"
"1","(1900,600)","0","pure_quanta","I56";
;
LOCATION"R3215"
$SEC"1"
CDS_SEC"1"
VALUE"0"
MATERIAL"EMPTY"
CDS_LIB"pure_quanta"
PACK_TYPE"0402LF"
WATTAGE"1/16W"
TOLERANCE"5%"
PART_NUMBER"CS00002JB13";
"B"
$PN"2"19;
"A"
$PN"1"39;
%"Q_RES"
"1","(1900,750)","0","pure_quanta","I60";
;
LOCATION"R3214"
$SEC"1"
CDS_SEC"1"
MATERIAL"EMPTY"
VALUE"0"
CDS_LIB"pure_quanta"
PACK_TYPE"0402LF"
WATTAGE"1/16W"
TOLERANCE"5%"
PART_NUMBER"CS00002JB13";
"B"
$PN"2"18;
"A"
$PN"1"40;
%"Q_RES"
"1","(1900,900)","0","pure_quanta","I61";
;
LOCATION"R3213"
$SEC"1"
CDS_SEC"1"
MATERIAL"EMPTY"
VALUE"0"
CDS_LIB"pure_quanta"
TOLERANCE"5%"
PACK_TYPE"0402LF"
WATTAGE"1/16W"
PART_NUMBER"CS00002JB13";
"B"
$PN"2"24;
"A"
$PN"1"41;
%"Q_RES"
"1","(1900,2025)","0","pure_quanta","I62";
;
LOCATION"R3212"
$SEC"1"
CDS_SEC"1"
MATERIAL"EMPTY"
VALUE"22"
CDS_LIB"pure_quanta"
PACK_TYPE"0402LF"
TOLERANCE"1%"
WATTAGE"1/16W"
PART_NUMBER"CS02202FB02";
"B"
$PN"2"17;
"A"
$PN"1"16;
%"Q_RES"
"1","(1900,2175)","0","pure_quanta","I63";
;
LOCATION"R3211"
$SEC"1"
CDS_SEC"1"
MATERIAL"EMPTY"
VALUE"22"
CDS_LIB"pure_quanta"
PACK_TYPE"0402LF"
TOLERANCE"1%"
WATTAGE"1/16W"
PART_NUMBER"CS02202FB02";
"B"
$PN"2"21;
"A"
$PN"1"22;
%"Q_RES"
"1","(3450,2475)","0","pure_quanta","I64";
;
LOCATION"R3209"
$SEC"1"
CDS_SEC"1"
MATERIAL"EMPTY"
PACK_TYPE"0402LF"
VALUE"22"
WATTAGE"1/16W"
TOLERANCE"1%"
CDS_LIB"pure_quanta"
PART_NUMBER"CS02202FB02";
"B"
$PN"2"25;
"A"
$PN"1"20;
%"Q_RES"
"1","(1900,2325)","0","pure_quanta","I65";
;
LOCATION"R3210"
$SEC"1"
CDS_SEC"1"
MATERIAL"EMPTY"
VALUE"22"
WATTAGE"1/16W"
TOLERANCE"1%"
PACK_TYPE"0402LF"
CDS_LIB"pure_quanta"
PART_NUMBER"CS02202FB02";
"B"
$PN"2"36;
"A"
$PN"1"28;
%"Q_CAP"
"1","(-525,1375)","2","pure_quanta","I77";
;
LOCATION"C1827"
$SEC"1"
CDS_SEC"1"
TOLERANCE"10%"
VOLTAGE"25V"
VALUE"0.1UF"
MATERIAL"X7R"
PACK_TYPE"0402"
CDS_LIB"pure_quanta"
PART_NUMBER"CH4104K1B00";
"B"
$PN"2"4;
"A"
$PN"1"35;
%"74CBTLV3126PW"
"1","(225,850)","2","pure_quanta","I78";
;
LOCATION"U223"
$SEC"1"
CDS_SEC"1"
PART_TYPE"SMLF"
MATERIAL"IC"
VALUE"74CBTLV3126PW"
CDS_LIB"pure_quanta"
NEEDS_NO_SIZE"TRUE"
CDS_LMAN_SYM_OUTLINE"-250,350,250,-350"
PART_NUMBER"AL003126K08";
"VCC"
$PN"14"35;
"4OE"
$PN"13"9;
"4A"
$PN"12"42;
"4B"
$PN"11"30;
"3OE"
$PN"10"9;
"3A"
$PN"9"41;
"GND"
$PN"7"3;
"1A"
$PN"2"39;
"2B"
$PN"6"31;
"1B"
$PN"3"38;
"2OE"
$PN"4"9;
"1OE"
$PN"1"9;
"3B"
$PN"8"15;
"2A"
$PN"5"40;
%"Q_RES"
"1","(3275,2275)","1","pure_quanta","I79";
;
LOCATION"R3244"
$SEC"1"
CDS_SEC"1"
MATERIAL"CHIP"
VALUE"0"
CDS_LIB"pure_quanta"
WATTAGE"1/16W"
PACK_TYPE"0402LF"
TOLERANCE"5%"
PART_NUMBER"CS00002JB13";
"B"
$PN"2"20;
"A"
$PN"1"42;
%"74LVC1G126SE7"
"1","(-1300,-425)","0","pure_quanta","I80";
;
LOCATION"U286"
$SEC"1"
CDS_SEC"1"
MATERIAL"IC"
VALUE"74LVC1G126SE-7"
PART_TYPE"SMLF"
NEEDS_NO_SIZE"TRUE"
CDS_LMAN_SYM_OUTLINE"-100,100,100,-100"
CDS_LIB"pure_quanta"
PART_NUMBER"AL1G0126009";
"OE"
$PN"1"12;
"GND"
$PN"3"7;
"VCC"
$PN"5"11;
"Y"
$PN"4"10;
"A"
$PN"2"13;
%"Q_RES"
"1","(-2875,-475)","0","pure_quanta","I81";
;
LOCATION"R3203"
$SEC"1"
CDS_SEC"1"
WATTAGE"1/16W"
PACK_TYPE"0402LF"
MATERIAL"CHIP"
TOLERANCE"1%"
VALUE"33.2"
CDS_LIB"pure_quanta"
PART_NUMBER"CS03322FB03";
"B"
$PN"2"12;
"A"
$PN"1"37;
%"UNIVERSAL_GND"
"1","(-1300,-800)","0","pure_quanta_power","I83";
;
CDS_LIB"pure_quanta_power"
HDL_POWER"GND";
"A"7;
%"Q_RES"
"1","(-75,-950)","0","pure_quanta","I85";
;
LOCATION"R3206"
$SEC"1"
CDS_SEC"1"
TOLERANCE"5%"
VALUE"0"
PACK_TYPE"0402LF"
WATTAGE"1/16W"
MATERIAL"EMPTY"
CDS_LIB"pure_quanta"
PART_NUMBER"CS00002JB13";
"B"
$PN"2"9;
"A"
$PN"1"8;
%"Q_RES"
"1","(-75,-425)","0","pure_quanta","I86";
;
LOCATION"R3205"
$SEC"1"
CDS_SEC"1"
VALUE"0"
PACK_TYPE"0402LF"
MATERIAL"CHIP"
TOLERANCE"5%"
WATTAGE"1/16W"
CDS_LIB"pure_quanta"
PART_NUMBER"CS00002JB13";
"B"
$PN"2"9;
"A"
$PN"1"10;
END.
